# S9S_MB_2U (Grand Teton) — schematic netlist excerpt (pin names and nets, part order shuffled) for the footprints in the layout excerpt that follows; sources: Cadence DE-HDL packaged netlist, KiCad conversion of 03242023_DA0F0TMBIJ0_F0T_Motherboard_J_brd_V01_OCP.brd

R256  Q_RES  240 1% EMPTY  pkg 0402LF  page 120 : A = PVNN_TERM_CPU1 ; B = FM_S3M_CPU1_LVC1_GPIO_1
C529  Q_CAP  47UF 4V 20% X6S  pkg C0805  page 76 : A = PVCCFA_EHV_FIVRA_CPU0 ; B = GND
C1902  Q_CAP  0.01UF 50V 10% X7R  pkg C0402  page 217 : A = P3V3_AUX_FPGA_VCCIO1 ; B = GND

(kicad_pcb
	(version 20260206)
	(generator "pcbnew")
	(generator_version "10.0")
	(general
		(thickness 1.6)
		(legacy_teardrops no)
	)
	(paper "A4")
	(title_block
		(title "03242023_DA0F0TMBIJ0_F0T_Motherboard_J_brd_V01_OCP.brd")
		(comment 1 "Grand Teton / footprints 4281-4283 of 6105")
	)
	(layers
		(0 "F.Cu" signal "TOP")
		(4 "In1.Cu" signal "GND")
		(6 "In2.Cu" signal "IN1")
		(8 "In3.Cu" signal "GND1")
		(10 "In4.Cu" signal "IN2")
		(12 "In5.Cu" signal "GND2")
		(14 "In6.Cu" signal "IN3")
		(16 "In7.Cu" signal "GND3")
		(18 "In8.Cu" signal "VCC")
		(20 "In9.Cu" signal "VCC1")
		(22 "In10.Cu" signal "GND4")
		(24 "In11.Cu" signal "IN4")
		(26 "In12.Cu" signal "GND5")
		(28 "In13.Cu" signal "IN5")
		(30 "In14.Cu" signal "GND6")
		(32 "In15.Cu" signal "IN6")
		(34 "In16.Cu" signal "GND7")
		(2 "B.Cu" signal "BOTTOM")
		(9 "F.Adhes" user "F.Adhesive")
		(11 "B.Adhes" user "B.Adhesive")
		(13 "F.Paste" user "Package Geometry/Pastemask Top")
		(15 "B.Paste" user "Package Geometry/Pastemask Bottom")
		(5 "F.SilkS" user "Ref Des/Silkscreen Top")
		(7 "B.SilkS" user "Ref Des/Silkscreen Bottom")
		(1 "F.Mask" user "Board Geometry/Soldermask Top")
		(3 "B.Mask" user "Board Geometry/Soldermask Bottom")
		(17 "Dwgs.User" user "User.Drawings")
		(19 "Cmts.User" user "User.Comments")
		(21 "Eco1.User" user "User.Eco1")
		(23 "Eco2.User" user "User.Eco2")
		(25 "Edge.Cuts" user "Board Geometry/Outline")
		(27 "Margin" user)
		(31 "F.CrtYd" user "Package Geometry/Place Bound Top")
		(29 "B.CrtYd" user "Package Geometry/Place Bound Bottom")
		(35 "F.Fab" user "Ref Des/Assembly Top")
		(33 "B.Fab" user "Ref Des/Assembly Bottom")
	)
	(footprint ""
		(layer "B.Cu")
		(at 178.55565 -118.575328)
		(property "Reference" "C1902"
			(at 0 0 0)
			(layer "B.SilkS")
			(hide yes)
			(effects
				(font
					(size 1.27 1.27)
				)
				(justify mirror)
			)
		)
		(property "Value" ""
			(at 0 0 0)
			(layer "B.Fab")
			(effects
				(font
					(size 1.27 1.27)
				)
				(justify mirror)
			)
		)
		(duplicate_pad_numbers_are_jumpers no)
		(fp_line
			(start -0.69215 -0.2921)
			(end -0.69215 0.2921)
			(stroke
				(width 0.1524)
				(type default)
			)
			(layer "B.SilkS")
		)
		(fp_line
			(start -0.69215 0.2921)
			(end 0.69215 0.2921)
			(stroke
				(width 0.1524)
				(type default)
			)
			(layer "B.SilkS")
		)
		(fp_line
			(start 0.69215 -0.2921)
			(end -0.69215 -0.2921)
			(stroke
				(width 0.1524)
				(type default)
			)
			(layer "B.SilkS")
		)
		(fp_line
			(start 0.69215 0.2921)
			(end 0.69215 -0.2921)
			(stroke
				(width 0.1524)
				(type default)
			)
			(layer "B.SilkS")
		)
		(fp_line
			(start -0.51435 -0.2794)
			(end -0.51435 0.2794)
			(stroke
				(width 0.1)
				(type default)
			)
			(layer "B.Fab")
		)
		(fp_line
			(start -0.51435 0.2794)
			(end 0.51435 0.2794)
			(stroke
				(width 0.1)
				(type default)
			)
			(layer "B.Fab")
		)
		(fp_line
			(start 0.51435 -0.2794)
			(end -0.51435 -0.2794)
			(stroke
				(width 0.1)
				(type default)
			)
			(layer "B.Fab")
		)
		(fp_line
			(start 0.51435 0.2794)
			(end 0.51435 -0.2794)
			(stroke
				(width 0.1)
				(type default)
			)
			(layer "B.Fab")
		)
		(pad "1" smd circle
			(at 0.40005 0 180)
			(size 0 0)
			(layers "B.Cu" "B.Mask" "B.Paste")
			(net "P3V3_AUX_FPGA_VCCIO1")
		)
		(pad "2" smd circle
			(at -0.40005 0 180)
			(size 0 0)
			(layers "B.Cu" "B.Mask" "B.Paste")
			(net "GND")
		)
		(zone
			(layer "B.Cu")
			(hatch none 0.5)
			(connect_pads
				(clearance 0)
			)
			(min_thickness 0.25)
			(keepout
				(tracks not_allowed)
				(vias allowed)
				(pads allowed)
				(copperpour not_allowed)
				(footprints allowed)
			)
			(placement
				(enabled no)
				(sheetname "")
			)
			(fill
				(thermal_gap 0.5)
				(thermal_bridge_width 0.5)
				(island_removal_mode 0)
			)
			(polygon
				(pts
					(xy 178.74615 -118.487698) (xy 178.65471 -118.429532) (xy 178.45532 -118.429532) (xy 178.36515 -118.487698)
					(xy 178.36515 -118.662958) (xy 178.45532 -118.721378) (xy 178.65471 -118.721378) (xy 178.74615 -118.663212)
				)
			)
		)
	)
	(footprint ""
		(layer "B.Cu")
		(at 46.634908 -193.25971 -90)
		(property "Reference" "R256"
			(at 0 0 90)
			(layer "B.SilkS")
			(hide yes)
			(effects
				(font
					(size 1.27 1.27)
				)
				(justify mirror)
			)
		)
		(property "Value" ""
			(at 0 0 90)
			(layer "B.Fab")
			(effects
				(font
					(size 1.27 1.27)
				)
				(justify mirror)
			)
		)
		(duplicate_pad_numbers_are_jumpers no)
		(fp_line
			(start -0.7874 0.4064)
			(end 0.7874 0.4064)
			(stroke
				(width 0.1524)
				(type default)
			)
			(layer "B.SilkS")
		)
		(fp_line
			(start 0.7874 0.4064)
			(end 0.7874 -0.4064)
			(stroke
				(width 0.1524)
				(type default)
			)
			(layer "B.SilkS")
		)
		(fp_line
			(start -0.7874 -0.4064)
			(end -0.7874 0.4064)
			(stroke
				(width 0.1524)
				(type default)
			)
			(layer "B.SilkS")
		)
		(fp_line
			(start 0.7874 -0.4064)
			(end -0.7874 -0.4064)
			(stroke
				(width 0.1524)
				(type default)
			)
			(layer "B.SilkS")
		)
		(fp_line
			(start -0.67945 0.3048)
			(end -0.120396 0.3048)
			(stroke
				(width 0.1)
				(type default)
			)
			(layer "B.Fab")
		)
		(fp_line
			(start -0.120396 0.3048)
			(end -0.120396 0.2794)
			(stroke
				(width 0.1)
				(type default)
			)
			(layer "B.Fab")
		)
		(fp_line
			(start 0.12065 0.3048)
			(end 0.67945 0.3048)
			(stroke
				(width 0.1)
				(type default)
			)
			(layer "B.Fab")
		)
		(fp_line
			(start 0.67945 0.3048)
			(end 0.67945 -0.305054)
			(stroke
				(width 0.1)
				(type default)
			)
			(layer "B.Fab")
		)
		(fp_line
			(start -0.120396 0.2794)
			(end 0.12065 0.2794)
			(stroke
				(width 0.1)
				(type default)
			)
			(layer "B.Fab")
		)
		(fp_line
			(start 0.12065 0.2794)
			(end 0.12065 0.3048)
			(stroke
				(width 0.1)
				(type default)
			)
			(layer "B.Fab")
		)
		(fp_line
			(start -0.12065 -0.2794)
			(end -0.12065 -0.3048)
			(stroke
				(width 0.1)
				(type default)
			)
			(layer "B.Fab")
		)
		(fp_line
			(start 0.12065 -0.2794)
			(end -0.12065 -0.2794)
			(stroke
				(width 0.1)
				(type default)
			)
			(layer "B.Fab")
		)
		(fp_line
			(start -0.67945 -0.3048)
			(end -0.67945 0.3048)
			(stroke
				(width 0.1)
				(type default)
			)
			(layer "B.Fab")
		)
		(fp_line
			(start -0.12065 -0.3048)
			(end -0.67945 -0.3048)
			(stroke
				(width 0.1)
				(type default)
			)
			(layer "B.Fab")
		)
		(fp_line
			(start 0.12065 -0.305054)
			(end 0.12065 -0.2794)
			(stroke
				(width 0.1)
				(type default)
			)
			(layer "B.Fab")
		)
		(fp_line
			(start 0.67945 -0.305054)
			(end 0.12065 -0.305054)
			(stroke
				(width 0.1)
				(type default)
			)
			(layer "B.Fab")
		)
		(pad "1" smd circle
			(at 0.40005 0 90)
			(size 0 0)
			(layers "B.Cu" "B.Mask" "B.Paste")
			(net "PVNN_TERM_CPU1")
		)
		(pad "2" smd circle
			(at -0.40005 0 90)
			(size 0 0)
			(layers "B.Cu" "B.Mask" "B.Paste")
			(net "FM_S3M_CPU1_LVC1_GPIO_1")
		)
	)
	(footprint ""
		(layer "B.Cu")
		(at 312.989214 -250.785376 90)
		(property "Reference" "C529"
			(at 0 0 90)
			(layer "B.SilkS")
			(hide yes)
			(effects
				(font
					(size 1.27 1.27)
				)
				(justify mirror)
			)
		)
		(property "Value" ""
			(at 0 0 90)
			(layer "B.Fab")
			(effects
				(font
					(size 1.27 1.27)
				)
				(justify mirror)
			)
		)
		(duplicate_pad_numbers_are_jumpers no)
		(fp_line
			(start 1.524 -0.762)
			(end -1.524 -0.762)
			(stroke
				(width 0.1524)
				(type default)
			)
			(layer "B.SilkS")
		)
		(fp_line
			(start -1.524 -0.762)
			(end -1.524 0.762)
			(stroke
				(width 0.1524)
				(type default)
			)
			(layer "B.SilkS")
		)
		(fp_line
			(start 1.524 0.762)
			(end 1.524 -0.762)
			(stroke
				(width 0.1524)
				(type default)
			)
			(layer "B.SilkS")
		)
		(fp_line
			(start -1.524 0.762)
			(end 1.524 0.762)
			(stroke
				(width 0.1524)
				(type default)
			)
			(layer "B.SilkS")
		)
		(fp_line
			(start 1.1049 -0.724916)
			(end 1.1049 0.724916)
			(stroke
				(width 0.1)
				(type default)
			)
			(layer "B.Fab")
		)
		(fp_line
			(start -1.1049 -0.724916)
			(end 1.1049 -0.724916)
			(stroke
				(width 0.1)
				(type default)
			)
			(layer "B.Fab")
		)
		(fp_line
			(start 1.1049 0.724916)
			(end -1.1049 0.724916)
			(stroke
				(width 0.1)
				(type default)
			)
			(layer "B.Fab")
		)
		(fp_line
			(start -1.1049 0.724916)
			(end -1.1049 -0.724916)
			(stroke
				(width 0.1)
				(type default)
			)
			(layer "B.Fab")
		)
		(pad "1" smd rect
			(at 0.889 0 90)
			(size 1.016 1.27)
			(layers "B.Cu" "B.Mask" "B.Paste")
			(net "PVCCFA_EHV_FIVRA_CPU0")
		)
		(pad "2" smd rect
			(at -0.889 0 90)
			(size 1.016 1.27)
			(layers "B.Cu" "B.Mask" "B.Paste")
			(net "GND")
		)
	)
)
